# BASEBOARD_FAB2 (Tioga Pass) — schematic netlist excerpt (pin names and nets, part order shuffled) for the footprints in the layout excerpt that follows; sources: Cadence DE-HDL packaged netlist, KiCad conversion of Wiwynn_Tioga_Pass_MB.brd

C7W8  SC22U16V5MX-4-GP  20%  pkg SMD-BCG5  page 220 : \1\ = VR_FET_SW_P12V_STBY_PVDDQ_DEF ; \2\ = GND
C2L13  CAP_A  0.01UF 25V 10% X7R  pkg 0402V  page 173 : A = SATA6G_PCH_PCIE_UP_SATA_RXN<2> ; B = SATA6G_P2_RX_C_DN
R1U64  RES  1.00K 1% CHIP  pkg 0402  page 137 : A = PD_IE_DEBUG_MODE ; B = GND

(kicad_pcb
	(version 20260206)
	(generator "pcbnew")
	(generator_version "10.0")
	(general
		(thickness 1.6)
		(legacy_teardrops no)
	)
	(paper "A4")
	(title_block
		(title "Wiwynn_Tioga_Pass_MB.brd")
		(comment 1 "Tioga Pass / footprints 4114-4116 of 4770")
	)
	(layers
		(0 "F.Cu" signal "TOP")
		(4 "In1.Cu" signal "L2GND")
		(6 "In2.Cu" signal "L3")
		(8 "In3.Cu" signal "L4GND")
		(10 "In4.Cu" signal "L5")
		(12 "In5.Cu" signal "L6GND")
		(14 "In6.Cu" signal "L7VCC")
		(16 "In7.Cu" signal "L8VCC")
		(18 "In8.Cu" signal "L9GND")
		(20 "In9.Cu" signal "L10")
		(22 "In10.Cu" signal "L11GND")
		(24 "In11.Cu" signal "L12")
		(26 "In12.Cu" signal "L13GND")
		(2 "B.Cu" signal "BOTTOM")
		(9 "F.Adhes" user "F.Adhesive")
		(11 "B.Adhes" user "B.Adhesive")
		(13 "F.Paste" user "Package Geometry/Pastemask Top")
		(15 "B.Paste" user "Package Geometry/Pastemask Bottom")
		(5 "F.SilkS" user "Ref Des/Silkscreen Top")
		(7 "B.SilkS" user "Ref Des/Silkscreen Bottom")
		(1 "F.Mask" user "Board Geometry/Soldermask Top")
		(3 "B.Mask" user "Board Geometry/Soldermask Bottom")
		(17 "Dwgs.User" user "User.Drawings")
		(19 "Cmts.User" user "User.Comments")
		(21 "Eco1.User" user "User.Eco1")
		(23 "Eco2.User" user "User.Eco2")
		(25 "Edge.Cuts" user "Board Geometry/Outline")
		(27 "Margin" user)
		(31 "F.CrtYd" user "Package Geometry/Place Bound Top")
		(29 "B.CrtYd" user "Package Geometry/Place Bound Bottom")
		(35 "F.Fab" user "Ref Des/Assembly Top")
		(33 "B.Fab" user "Ref Des/Assembly Bottom")
	)
	(footprint ""
		(layer "B.Cu")
		(at 420.624 -151.765 90)
		(property "Reference" "C2L13"
			(at 0 0 90)
			(layer "B.SilkS")
			(hide yes)
			(effects
				(font
					(size 1.27 1.27)
				)
				(justify mirror)
			)
		)
		(property "Value" ""
			(at 0 0 90)
			(layer "B.Fab")
			(effects
				(font
					(size 1.27 1.27)
				)
				(justify mirror)
			)
		)
		(duplicate_pad_numbers_are_jumpers no)
		(fp_poly
			(pts
				(xy -0.3048 -0.1016) (xy -0.3048 0.9906) (xy 0.3048 0.9906) (xy 0.3048 -0.1016)
			)
			(stroke
				(width 0)
				(type default)
			)
			(fill no)
			(layer "B.CrtYd")
		)
		(fp_line
			(start 0.3048 -0.1016)
			(end 0.3048 0.9906)
			(stroke
				(width 0.1)
				(type default)
			)
			(layer "B.Fab")
		)
		(fp_line
			(start -0.3048 -0.1016)
			(end 0.3048 -0.1016)
			(stroke
				(width 0.1)
				(type default)
			)
			(layer "B.Fab")
		)
		(fp_line
			(start 0.3048 0.9906)
			(end -0.3048 0.9906)
			(stroke
				(width 0.1)
				(type default)
			)
			(layer "B.Fab")
		)
		(fp_line
			(start -0.3048 0.9906)
			(end -0.3048 -0.1016)
			(stroke
				(width 0.1)
				(type default)
			)
			(layer "B.Fab")
		)
		(pad "1" smd rect
			(at 0 0 270)
			(size 0.508 0.508)
			(layers "B.Cu" "B.Mask" "B.Paste")
			(net "SATA6G_PCH_PCIE_UP_SATA_RXN<2>")
		)
		(pad "2" smd rect
			(at 0 0.889 270)
			(size 0.508 0.508)
			(layers "B.Cu" "B.Mask" "B.Paste")
			(net "SATA6G_P2_RX_C_DN")
		)
		(zone
			(layer "B.Cu")
			(hatch none 0.5)
			(connect_pads
				(clearance 0)
			)
			(min_thickness 0.25)
			(keepout
				(tracks allowed)
				(vias not_allowed)
				(pads allowed)
				(copperpour not_allowed)
				(footprints allowed)
			)
			(placement
				(enabled no)
				(sheetname "")
			)
			(fill
				(thermal_gap 0.5)
				(thermal_bridge_width 0.5)
				(island_removal_mode 0)
			)
			(polygon
				(pts
					(xy 420.878 -152.019) (xy 420.878 -151.511) (xy 421.259 -151.511) (xy 421.259 -152.019)
				)
			)
		)
		(zone
			(layer "B.Cu")
			(hatch none 0.5)
			(connect_pads
				(clearance 0)
			)
			(min_thickness 0.25)
			(keepout
				(tracks not_allowed)
				(vias allowed)
				(pads allowed)
				(copperpour not_allowed)
				(footprints allowed)
			)
			(placement
				(enabled no)
				(sheetname "")
			)
			(fill
				(thermal_gap 0.5)
				(thermal_bridge_width 0.5)
				(island_removal_mode 0)
			)
			(polygon
				(pts
					(xy 421.259 -152.019) (xy 421.259 -151.511) (xy 420.878 -151.511) (xy 420.878 -152.019)
				)
			)
		)
	)
	(footprint ""
		(layer "B.Cu")
		(at 357.988616 -146.777202)
		(property "Reference" "C7W8"
			(at 0 0 0)
			(layer "B.SilkS")
			(hide yes)
			(effects
				(font
					(size 1.27 1.27)
				)
				(justify mirror)
			)
		)
		(property "Value" "*"
			(at 0.0762 -6.2357 0)
			(unlocked yes)
			(layer "B.Fab")
			(hide yes)
			(effects
				(font
					(size 1.27 1.016)
					(thickness 0.1524)
				)
				(justify mirror)
			)
		)
		(property "Device Type" "SC22U16V5MX-4-GP_SMD-BCG5-SC22A"
			(at 0.0762 -8.2677 0)
			(unlocked yes)
			(layer "B.Fab")
			(hide yes)
			(effects
				(font
					(size 1.27 1.016)
					(thickness 0.1524)
				)
				(justify mirror)
			)
		)
		(duplicate_pad_numbers_are_jumpers no)
		(fp_line
			(start -0.635 0)
			(end 0.635 0)
			(stroke
				(width 0.508)
				(type default)
			)
			(layer "B.SilkS")
		)
		(fp_rect
			(start 0.9652 1.778)
			(end -0.9652 -1.778)
			(stroke
				(width 0)
				(type default)
			)
			(fill no)
			(layer "B.CrtYd")
		)
		(fp_poly
			(pts
				(xy 0.9652 -1.778) (xy -0.9652 -1.778) (xy -0.9652 1.778) (xy 0.9652 1.778)
			)
			(stroke
				(width 0)
				(type default)
			)
			(fill no)
			(layer "B.Fab")
		)
		(pad "1" smd rect
			(at 0 -0.9652 180)
			(size 1.397 1.143)
			(layers "B.Cu" "B.Mask" "B.Paste")
			(net "VR_FET_SW_P12V_STBY_PVDDQ_DEF")
		)
		(pad "2" smd rect
			(at 0 0.9652 180)
			(size 1.397 1.143)
			(layers "B.Cu" "B.Mask" "B.Paste")
			(net "GND")
		)
	)
	(footprint ""
		(layer "B.Cu")
		(at 452.35241 -4.614672 90)
		(property "Reference" "R1U64"
			(at 0 0 90)
			(layer "B.SilkS")
			(hide yes)
			(effects
				(font
					(size 1.27 1.27)
				)
				(justify mirror)
			)
		)
		(property "Value" ""
			(at 0 0 90)
			(layer "B.Fab")
			(effects
				(font
					(size 1.27 1.27)
				)
				(justify mirror)
			)
		)
		(duplicate_pad_numbers_are_jumpers no)
		(fp_poly
			(pts
				(xy 0.2794 -0.1016) (xy -0.2794 -0.1016) (xy -0.2794 0.990854) (xy 0.2794 0.990854)
			)
			(stroke
				(width 0)
				(type default)
			)
			(fill no)
			(layer "B.CrtYd")
		)
		(fp_line
			(start 0.2794 -0.1016)
			(end 0.2794 0.990854)
			(stroke
				(width 0.1)
				(type default)
			)
			(layer "B.Fab")
		)
		(fp_line
			(start -0.2794 -0.1016)
			(end 0.2794 -0.1016)
			(stroke
				(width 0.1)
				(type default)
			)
			(layer "B.Fab")
		)
		(fp_line
			(start 0.2794 0.990854)
			(end -0.2794 0.990854)
			(stroke
				(width 0.1)
				(type default)
			)
			(layer "B.Fab")
		)
		(fp_line
			(start -0.2794 0.990854)
			(end -0.2794 -0.1016)
			(stroke
				(width 0.1)
				(type default)
			)
			(layer "B.Fab")
		)
		(pad "1" smd rect
			(at 0 0 270)
			(size 0.508 0.508)
			(layers "B.Cu" "B.Mask" "B.Paste")
			(net "PD_IE_DEBUG_MODE")
		)
		(pad "2" smd rect
			(at 0 0.889 270)
			(size 0.508 0.508)
			(layers "B.Cu" "B.Mask" "B.Paste")
			(net "GND")
		)
		(zone
			(layer "B.Cu")
			(hatch none 0.5)
			(connect_pads
				(clearance 0)
			)
			(min_thickness 0.25)
			(keepout
				(tracks allowed)
				(vias not_allowed)
				(pads allowed)
				(copperpour not_allowed)
				(footprints allowed)
			)
			(placement
				(enabled no)
				(sheetname "")
			)
			(fill
				(thermal_gap 0.5)
				(thermal_bridge_width 0.5)
				(island_removal_mode 0)
			)
			(polygon
				(pts
					(xy 452.60641 -4.868672) (xy 452.60641 -4.360672) (xy 452.987664 -4.360672) (xy 452.987664 -4.868672)
				)
			)
		)
		(zone
			(layer "B.Cu")
			(hatch none 0.5)
			(connect_pads
				(clearance 0)
			)
			(min_thickness 0.25)
			(keepout
				(tracks not_allowed)
				(vias allowed)
				(pads allowed)
				(copperpour not_allowed)
				(footprints allowed)
			)
			(placement
				(enabled no)
				(sheetname "")
			)
			(fill
				(thermal_gap 0.5)
				(thermal_bridge_width 0.5)
				(island_removal_mode 0)
			)
			(polygon
				(pts
					(xy 452.987664 -4.868672) (xy 452.987664 -4.360672) (xy 452.60641 -4.360672) (xy 452.60641 -4.868672)
				)
			)
		)
	)
)
